(kicad_pcb
	(version 20260206)
	(generator "pcbnew")
	(generator_version "10.0")
	(general
		(thickness 1.6)
		(legacy_teardrops no)
	)
	(paper "A4")
	(title_block
		(title "Wiwynn_Tioga_Pass_MB.brd")
		(comment 1 "Tioga Pass / footprints 1749-1753 of 4770")
	)
	(layers
		(0 "F.Cu" signal "TOP")
		(4 "In1.Cu" signal "L2GND")
		(6 "In2.Cu" signal "L3")
		(8 "In3.Cu" signal "L4GND")
		(10 "In4.Cu" signal "L5")
		(12 "In5.Cu" signal "L6GND")
		(14 "In6.Cu" signal "L7VCC")
		(16 "In7.Cu" signal "L8VCC")
		(18 "In8.Cu" signal "L9GND")
		(20 "In9.Cu" signal "L10")
		(22 "In10.Cu" signal "L11GND")
		(24 "In11.Cu" signal "L12")
		(26 "In12.Cu" signal "L13GND")
		(2 "B.Cu" signal "BOTTOM")
		(9 "F.Adhes" user "F.Adhesive")
		(11 "B.Adhes" user "B.Adhesive")
		(13 "F.Paste" user "Package Geometry/Pastemask Top")
		(15 "B.Paste" user "Package Geometry/Pastemask Bottom")
		(5 "F.SilkS" user "Ref Des/Silkscreen Top")
		(7 "B.SilkS" user "Ref Des/Silkscreen Bottom")
		(1 "F.Mask" user "Board Geometry/Soldermask Top")
		(3 "B.Mask" user "Board Geometry/Soldermask Bottom")
		(17 "Dwgs.User" user "User.Drawings")
		(19 "Cmts.User" user "User.Comments")
		(21 "Eco1.User" user "User.Eco1")
		(23 "Eco2.User" user "User.Eco2")
		(25 "Edge.Cuts" user "Board Geometry/Outline")
		(27 "Margin" user)
		(31 "F.CrtYd" user "Package Geometry/Place Bound Top")
		(29 "B.CrtYd" user "Package Geometry/Place Bound Bottom")
		(35 "F.Fab" user "Ref Des/Assembly Top")
		(33 "B.Fab" user "Ref Des/Assembly Bottom")
	)
	(footprint ""
		(layer "F.Cu")
		(at 449.454016 3.81 90)
		(property "Reference" "J9G1"
			(at 1.524 -2.13233 90)
			(unlocked yes)
			(layer "B.SilkS")
			(effects
				(font
					(size 0.7874 0.5842)
					(thickness 0.1524)
				)
				(justify mirror)
			)
		)
		(property "Value" ""
			(at 0 0 90)
			(layer "F.Fab")
			(effects
				(font
					(size 1.27 1.27)
				)
			)
		)
		(duplicate_pad_numbers_are_jumpers no)
		(fp_line
			(start 3.8227 -1.27)
			(end 3.8227 13.97)
			(stroke
				(width 0.1524)
				(type default)
			)
			(layer "F.SilkS")
		)
		(fp_line
			(start -1.2827 -1.27)
			(end 3.8227 -1.27)
			(stroke
				(width 0.1524)
				(type default)
			)
			(layer "F.SilkS")
		)
		(fp_line
			(start 3.7592 -1.143)
			(end 3.758184 -1.143)
			(stroke
				(width 0.1)
				(type default)
			)
			(layer "F.SilkS")
		)
		(fp_line
			(start -1.2192 -1.143)
			(end -1.218946 -1.143)
			(stroke
				(width 0.1)
				(type default)
			)
			(layer "F.SilkS")
		)
		(fp_line
			(start 3.7592 13.843)
			(end 3.758946 13.843)
			(stroke
				(width 0.1524)
				(type default)
			)
			(layer "F.SilkS")
		)
		(fp_line
			(start -1.2192 13.843)
			(end -1.218946 13.843)
			(stroke
				(width 0.1524)
				(type default)
			)
			(layer "F.SilkS")
		)
		(fp_line
			(start 3.8227 13.97)
			(end -1.2827 13.97)
			(stroke
				(width 0.1524)
				(type default)
			)
			(layer "F.SilkS")
		)
		(fp_line
			(start -1.2827 13.97)
			(end -1.2827 -1.27)
			(stroke
				(width 0.1524)
				(type default)
			)
			(layer "F.SilkS")
		)
		(fp_poly
			(pts
				(xy -1.7145 -0.005588) (xy -2.9845 0.502412) (xy -2.9845 -0.513588)
			)
			(stroke
				(width 0)
				(type default)
			)
			(fill yes)
			(layer "F.SilkS")
		)
		(fp_poly
			(pts
				(xy -1.7145 -0.005588) (xy -2.9845 0.502412) (xy -2.9845 -0.513588)
			)
			(stroke
				(width 0)
				(type default)
			)
			(fill yes)
			(layer "B.SilkS")
		)
		(fp_poly
			(pts
				(xy -1.2827 -1.27) (xy -1.2827 13.97) (xy 3.8227 13.97) (xy 3.8227 -1.27)
			)
			(stroke
				(width 0)
				(type default)
			)
			(fill no)
			(layer "F.CrtYd")
		)
		(fp_poly
			(pts
				(xy -1.7145 -0.005588) (xy -2.9845 0.502412) (xy -2.9845 -0.513588)
			)
			(stroke
				(width 0)
				(type default)
			)
			(fill yes)
			(layer "B.Fab")
		)
		(fp_line
			(start 3.8227 -1.27)
			(end -1.2827 -1.27)
			(stroke
				(width 0.1)
				(type default)
			)
			(layer "F.Fab")
		)
		(fp_line
			(start -1.2827 -1.27)
			(end -1.2827 13.97)
			(stroke
				(width 0.1)
				(type default)
			)
			(layer "F.Fab")
		)
		(fp_line
			(start 3.8227 13.97)
			(end 3.8227 -1.27)
			(stroke
				(width 0.1)
				(type default)
			)
			(layer "F.Fab")
		)
		(fp_line
			(start -1.2827 13.97)
			(end 3.8227 13.97)
			(stroke
				(width 0.1)
				(type default)
			)
			(layer "F.Fab")
		)
		(fp_poly
			(pts
				(xy -1.7145 -0.005588) (xy -2.9845 0.502412) (xy -2.9845 -0.513588)
			)
			(stroke
				(width 0)
				(type default)
			)
			(fill yes)
			(layer "F.Fab")
		)
		(fp_text user "2"
			(at 2.832354 -1.784096 0)
			(unlocked yes)
			(layer "F.SilkS")
			(effects
				(font
					(size 0.7874 0.5842)
					(thickness 0.1524)
				)
			)
		)
		(fp_text user "12"
			(at 4.391914 12.930124 0)
			(unlocked yes)
			(layer "F.SilkS")
			(effects
				(font
					(size 0.7874 0.5842)
					(thickness 0.1524)
				)
			)
		)
		(fp_text user "11"
			(at -0.980186 14.880336 0)
			(unlocked yes)
			(layer "F.SilkS")
			(effects
				(font
					(size 0.7874 0.5842)
					(thickness 0.1524)
				)
			)
		)
		(fp_text user "2"
			(at 4.5466 0.02667 90)
			(unlocked yes)
			(layer "B.SilkS")
			(effects
				(font
					(size 0.7874 0.5842)
					(thickness 0.1524)
				)
				(justify mirror)
			)
		)
		(fp_text user "11"
			(at -2.2606 12.72667 90)
			(unlocked yes)
			(layer "B.SilkS")
			(effects
				(font
					(size 0.7874 0.5842)
					(thickness 0.1524)
				)
				(justify mirror)
			)
		)
		(fp_text user "12"
			(at 2.6797 14.37767 90)
			(unlocked yes)
			(layer "B.SilkS")
			(effects
				(font
					(size 0.7874 0.5842)
					(thickness 0.1524)
				)
				(justify mirror)
			)
		)
		(fp_text user "2"
			(at 4.5466 0.02667 90)
			(unlocked yes)
			(layer "B.Fab")
			(effects
				(font
					(size 0.7874 0.5842)
					(thickness 0.1524)
				)
				(justify mirror)
			)
		)
		(fp_text user "11"
			(at -2.2606 12.72667 90)
			(unlocked yes)
			(layer "B.Fab")
			(effects
				(font
					(size 0.7874 0.5842)
					(thickness 0.1524)
				)
				(justify mirror)
			)
		)
		(fp_text user "12"
			(at 2.6797 14.37767 90)
			(unlocked yes)
			(layer "B.Fab")
			(effects
				(font
					(size 0.7874 0.5842)
					(thickness 0.1524)
				)
				(justify mirror)
			)
		)
		(fp_text user "2"
			(at 4.572 -1.36271 90)
			(unlocked yes)
			(layer "F.Fab")
			(effects
				(font
					(size 0.7874 0.5842)
					(thickness 0.1524)
				)
			)
		)
		(fp_text user "11"
			(at -2.02692 13.66139 90)
			(unlocked yes)
			(layer "F.Fab")
			(effects
				(font
					(size 0.7874 0.5842)
					(thickness 0.1524)
				)
			)
		)
		(fp_text user "12"
			(at 5.334 14.13129 90)
			(unlocked yes)
			(layer "F.Fab")
			(effects
				(font
					(size 0.7874 0.5842)
					(thickness 0.1524)
				)
			)
		)
		(pad "1" thru_hole rect
			(at 0 0 90)
			(size 1.6256 1.6256)
			(drill 1.2446)
			(layers "*.Cu" "*.Mask")
			(remove_unused_layers no)
			(net "PU_UV_HIGH_SET")
			(clearance 0.127)
			(thermal_gap 0.127)
			(padstack
				(mode front_inner_back)
				(layer "Inner"
					(shape circle)
					(size 1.6256 1.6256)
					(clearance 0.127)
				)
				(layer "B.Cu"
					(shape rect)
					(size 1.6256 1.6256)
					(clearance 0.127)
				)
			)
		)
		(pad "2" thru_hole circle
			(at 2.54 0 90)
			(size 1.6256 1.6256)
			(drill 1.2446)
			(layers "*.Cu" "*.Mask")
			(remove_unused_layers no)
			(net "TP_RST_RTCRST_N")
			(clearance 0.127)
			(thermal_gap 0.127)
		)
		(pad "3" thru_hole circle
			(at 0 2.54 90)
			(size 1.6256 1.6256)
			(drill 1.2446)
			(layers "*.Cu" "*.Mask")
			(remove_unused_layers no)
			(net "UV_HIGH_SET")
			(clearance 0.127)
			(thermal_gap 0.127)
		)
		(pad "4" thru_hole circle
			(at 2.54 2.54 90)
			(size 1.6256 1.6256)
			(drill 1.2446)
			(layers "*.Cu" "*.Mask")
			(remove_unused_layers no)
			(net "RST_RTCRST_N")
			(clearance 0.127)
			(thermal_gap 0.127)
		)
		(pad "5" thru_hole circle
			(at 0 5.08 90)
			(size 1.6256 1.6256)
			(drill 1.2446)
			(layers "*.Cu" "*.Mask")
			(remove_unused_layers no)
			(net "PD_UV_HIGH_SET")
			(clearance 0.127)
			(thermal_gap 0.127)
		)
		(pad "6" thru_hole circle
			(at 2.54 5.08 90)
			(size 1.6256 1.6256)
			(drill 1.2446)
			(layers "*.Cu" "*.Mask")
			(remove_unused_layers no)
			(net "PD_RST_RTCRST_N")
			(clearance 0.127)
			(thermal_gap 0.127)
		)
		(pad "7" thru_hole circle
			(at 0 7.62 90)
			(size 1.6256 1.6256)
			(drill 1.2446)
			(layers "*.Cu" "*.Mask")
			(remove_unused_layers no)
			(net "TP_IE_DEBUG_MODE")
			(clearance 0.127)
			(thermal_gap 0.127)
		)
		(pad "8" thru_hole circle
			(at 2.54 7.62 90)
			(size 1.6256 1.6256)
			(drill 1.2446)
			(layers "*.Cu" "*.Mask")
			(remove_unused_layers no)
			(net "PU_SPI_BMC_BT_CS0_N")
			(clearance 0.127)
			(thermal_gap 0.127)
		)
		(pad "9" thru_hole circle
			(at 0 10.16 90)
			(size 1.6256 1.6256)
			(drill 1.2446)
			(layers "*.Cu" "*.Mask")
			(remove_unused_layers no)
			(net "FM_UART_PRES_N")
			(clearance 0.127)
			(thermal_gap 0.127)
		)
		(pad "10" thru_hole circle
			(at 2.54 10.16 90)
			(size 1.6256 1.6256)
			(drill 1.2446)
			(layers "*.Cu" "*.Mask")
			(remove_unused_layers no)
			(net "SPI_BMC_BT_CS0_N")
			(clearance 0.127)
			(thermal_gap 0.127)
		)
		(pad "11" thru_hole circle
			(at 0 12.7 90)
			(size 1.6256 1.6256)
			(drill 1.2446)
			(layers "*.Cu" "*.Mask")
			(remove_unused_layers no)
			(net "PD_IE_DEBUG_MODE")
			(clearance 0.127)
			(thermal_gap 0.127)
		)
		(pad "12" thru_hole circle
			(at 2.54 12.7 90)
			(size 1.6256 1.6256)
			(drill 1.2446)
			(layers "*.Cu" "*.Mask")
			(remove_unused_layers no)
			(net "PD_SPI_BMC_BT_CS0_N")
			(clearance 0.127)
			(thermal_gap 0.127)
		)
	)
	(footprint ""
		(layer "F.Cu")
		(at 14.224 -101.981)
		(property "Reference" "R1C10"
			(at 0 0 0)
			(layer "F.SilkS")
			(hide yes)
			(effects
				(font
					(size 1.27 1.27)
				)
			)
		)
		(property "Value" ""
			(at 0 0 0)
			(layer "F.Fab")
			(effects
				(font
					(size 1.27 1.27)
				)
			)
		)
		(duplicate_pad_numbers_are_jumpers no)
		(fp_poly
			(pts
				(xy -0.2794 -0.1016) (xy 0.2794 -0.1016) (xy 0.2794 0.9906) (xy -0.2794 0.9906)
			)
			(stroke
				(width 0)
				(type default)
			)
			(fill no)
			(layer "F.CrtYd")
		)
		(fp_line
			(start -0.2794 -0.1016)
			(end -0.2794 0.9906)
			(stroke
				(width 0.1)
				(type default)
			)
			(layer "F.Fab")
		)
		(fp_line
			(start -0.2794 0.9906)
			(end 0.2794 0.9906)
			(stroke
				(width 0.1)
				(type default)
			)
			(layer "F.Fab")
		)
		(fp_line
			(start 0.2794 -0.1016)
			(end -0.2794 -0.1016)
			(stroke
				(width 0.1)
				(type default)
			)
			(layer "F.Fab")
		)
		(fp_line
			(start 0.2794 0.9906)
			(end 0.2794 -0.1016)
			(stroke
				(width 0.1)
				(type default)
			)
			(layer "F.Fab")
		)
		(pad "1" smd rect
			(at 0 0)
			(size 0.508 0.508)
			(layers "F.Cu" "F.Mask" "F.Paste")
			(net "SMB_LAN_STBY_LVC3_SDA")
		)
		(pad "2" smd rect
			(at 0 0.889)
			(size 0.508 0.508)
			(layers "F.Cu" "F.Mask" "F.Paste")
			(net "FAN_TACH3_R")
		)
		(zone
			(layer "F.Cu")
			(hatch none 0.5)
			(connect_pads
				(clearance 0)
			)
			(min_thickness 0.25)
			(keepout
				(tracks allowed)
				(vias not_allowed)
				(pads allowed)
				(copperpour not_allowed)
				(footprints allowed)
			)
			(placement
				(enabled no)
				(sheetname "")
			)
			(fill
				(thermal_gap 0.5)
				(thermal_bridge_width 0.5)
				(island_removal_mode 0)
			)
			(polygon
				(pts
					(xy 13.97 -101.727) (xy 14.478 -101.727) (xy 14.478 -101.346) (xy 13.97 -101.346)
				)
			)
		)
		(zone
			(layer "F.Cu")
			(hatch none 0.5)
			(connect_pads
				(clearance 0)
			)
			(min_thickness 0.25)
			(keepout
				(tracks not_allowed)
				(vias allowed)
				(pads allowed)
				(copperpour not_allowed)
				(footprints allowed)
			)
			(placement
				(enabled no)
				(sheetname "")
			)
			(fill
				(thermal_gap 0.5)
				(thermal_bridge_width 0.5)
				(island_removal_mode 0)
			)
			(polygon
				(pts
					(xy 13.97 -101.346) (xy 14.478 -101.346) (xy 14.478 -101.727) (xy 13.97 -101.727)
				)
			)
		)
	)
	(footprint ""
		(layer "F.Cu")
		(at 356.98684 -134.22757)
		(property "Reference" "C7B2"
			(at 0 0 0)
			(layer "F.SilkS")
			(hide yes)
			(effects
				(font
					(size 1.27 1.27)
				)
			)
		)
		(property "Value" ""
			(at 0 0 0)
			(layer "F.Fab")
			(effects
				(font
					(size 1.27 1.27)
				)
			)
		)
		(duplicate_pad_numbers_are_jumpers no)
		(fp_rect
			(start -0.3048 0.9906)
			(end 0.3048 -0.1016)
			(stroke
				(width 0)
				(type default)
			)
			(fill no)
			(layer "F.CrtYd")
		)
		(fp_line
			(start -0.3048 -0.1016)
			(end -0.3048 0.9906)
			(stroke
				(width 0.1)
				(type default)
			)
			(layer "F.Fab")
		)
		(fp_line
			(start -0.3048 0.9906)
			(end 0.3048 0.9906)
			(stroke
				(width 0.1)
				(type default)
			)
			(layer "F.Fab")
		)
		(fp_line
			(start 0.3048 -0.1016)
			(end -0.3048 -0.1016)
			(stroke
				(width 0.1)
				(type default)
			)
			(layer "F.Fab")
		)
		(fp_line
			(start 0.3048 0.9906)
			(end 0.3048 -0.1016)
			(stroke
				(width 0.1)
				(type default)
			)
			(layer "F.Fab")
		)
		(pad "1" smd rect
			(at 0 0)
			(size 0.508 0.508)
			(layers "F.Cu" "F.Mask" "F.Paste")
			(net "VR_PVDDQ_DEF_VD12")
		)
		(pad "2" smd rect
			(at 0 0.889)
			(size 0.508 0.508)
			(layers "F.Cu" "F.Mask" "F.Paste")
			(net "GND")
		)
		(zone
			(layer "F.Cu")
			(hatch none 0.5)
			(connect_pads
				(clearance 0)
			)
			(min_thickness 0.25)
			(keepout
				(tracks allowed)
				(vias not_allowed)
				(pads allowed)
				(copperpour not_allowed)
				(footprints allowed)
			)
			(placement
				(enabled no)
				(sheetname "")
			)
			(fill
				(thermal_gap 0.5)
				(thermal_bridge_width 0.5)
				(island_removal_mode 0)
			)
			(polygon
				(pts
					(xy 356.73284 -133.59257) (xy 357.24084 -133.59257) (xy 357.24084 -133.97357) (xy 356.73284 -133.97357)
				)
			)
		)
		(zone
			(layer "F.Cu")
			(hatch none 0.5)
			(connect_pads
				(clearance 0)
			)
			(min_thickness 0.25)
			(keepout
				(tracks not_allowed)
				(vias allowed)
				(pads allowed)
				(copperpour not_allowed)
				(footprints allowed)
			)
			(placement
				(enabled no)
				(sheetname "")
			)
			(fill
				(thermal_gap 0.5)
				(thermal_bridge_width 0.5)
				(island_removal_mode 0)
			)
			(polygon
				(pts
					(xy 356.73284 -133.59257) (xy 357.24084 -133.59257) (xy 357.24084 -133.97357) (xy 356.73284 -133.97357)
				)
			)
		)
	)
	(footprint ""
		(layer "F.Cu")
		(at 353.216464 -144.502378 -90)
		(property "Reference" "RT31"
			(at 1.01473 0.656336 180)
			(unlocked yes)
			(layer "F.SilkS")
			(effects
				(font
					(size 0.4064 0.254)
					(thickness 0.1524)
				)
			)
		)
		(property "Value" ""
			(at 0 0 270)
			(layer "F.Fab")
			(effects
				(font
					(size 1.27 1.27)
				)
			)
		)
		(duplicate_pad_numbers_are_jumpers no)
		(fp_poly
			(pts
				(xy -0.4953 -0.2032) (xy 0.4953 -0.2032) (xy 0.4953 1.6002) (xy -0.4953 1.6002)
			)
			(stroke
				(width 0)
				(type default)
			)
			(fill no)
			(layer "F.CrtYd")
		)
		(fp_line
			(start -0.4953 1.6002)
			(end -0.4953 -0.2032)
			(stroke
				(width 0.1)
				(type default)
			)
			(layer "F.Fab")
		)
		(fp_line
			(start 0.4953 1.6002)
			(end -0.4953 1.6002)
			(stroke
				(width 0.1)
				(type default)
			)
			(layer "F.Fab")
		)
		(fp_line
			(start -0.4953 -0.2032)
			(end 0.4953 -0.2032)
			(stroke
				(width 0.1)
				(type default)
			)
			(layer "F.Fab")
		)
		(fp_line
			(start 0.4953 -0.2032)
			(end 0.4953 1.6002)
			(stroke
				(width 0.1)
				(type default)
			)
			(layer "F.Fab")
		)
		(pad "1" smd rect
			(at 0 0 270)
			(size 0.762 0.889)
			(layers "F.Cu" "F.Mask" "F.Paste")
			(net "VR_PVDDQ_DEF_PH2_BOOT")
		)
		(pad "2" smd rect
			(at 0 1.397 270)
			(size 0.762 0.889)
			(layers "F.Cu" "F.Mask" "F.Paste")
			(net "VR_PVDDQ_DEF_PH2_BOOT_R")
		)
		(zone
			(layer "F.Cu")
			(hatch none 0.5)
			(connect_pads
				(clearance 0)
			)
			(min_thickness 0.25)
			(keepout
				(tracks not_allowed)
				(vias allowed)
				(pads allowed)
				(copperpour not_allowed)
				(footprints allowed)
			)
			(placement
				(enabled no)
				(sheetname "")
			)
			(fill
				(thermal_gap 0.5)
				(thermal_bridge_width 0.5)
				(island_removal_mode 0)
			)
			(polygon
				(pts
					(xy 352.263964 -144.883378) (xy 352.263964 -144.121378) (xy 352.771964 -144.121378) (xy 352.771964 -144.883378)
				)
			)
		)
		(zone
			(layer "F.Cu")
			(hatch none 0.5)
			(connect_pads
				(clearance 0)
			)
			(min_thickness 0.25)
			(keepout
				(tracks allowed)
				(vias not_allowed)
				(pads allowed)
				(copperpour not_allowed)
				(footprints allowed)
			)
			(placement
				(enabled no)
				(sheetname "")
			)
			(fill
				(thermal_gap 0.5)
				(thermal_bridge_width 0.5)
				(island_removal_mode 0)
			)
			(polygon
				(pts
					(xy 352.263964 -144.121378) (xy 352.771964 -144.121378) (xy 352.771964 -144.883378) (xy 352.263964 -144.883378)
				)
			)
		)
	)
	(footprint ""
		(layer "F.Cu")
		(at 83.856068 -3.3528 -90)
		(property "Reference" "C2G10"
			(at 1.848866 0.752348 270)
			(unlocked yes)
			(layer "F.SilkS")
			(effects
				(font
					(size 1.27 0.9652)
					(thickness 0.1524)
				)
			)
		)
		(property "Value" ""
			(at 0 0 270)
			(layer "F.Fab")
			(effects
				(font
					(size 1.27 1.27)
				)
			)
		)
		(duplicate_pad_numbers_are_jumpers no)
		(fp_rect
			(start -0.500126 1.598422)
			(end 0.500126 -0.201422)
			(stroke
				(width 0)
				(type default)
			)
			(fill no)
			(layer "F.CrtYd")
		)
		(fp_line
			(start -0.500126 1.598422)
			(end -0.500126 -0.201422)
			(stroke
				(width 0.1)
				(type default)
			)
			(layer "F.Fab")
		)
		(fp_line
			(start 0.500126 1.598422)
			(end -0.500126 1.598422)
			(stroke
				(width 0.1)
				(type default)
			)
			(layer "F.Fab")
		)
		(fp_line
			(start -0.500126 -0.201422)
			(end 0.500126 -0.201422)
			(stroke
				(width 0.1)
				(type default)
			)
			(layer "F.Fab")
		)
		(fp_line
			(start 0.500126 -0.201422)
			(end 0.500126 1.598422)
			(stroke
				(width 0.1)
				(type default)
			)
			(layer "F.Fab")
		)
		(pad "1" smd rect
			(at 0 0 180)
			(size 0.889 0.9906)
			(layers "F.Cu" "F.Mask" "F.Paste")
			(net "PVDDQ_GHJ")
		)
		(pad "2" smd rect
			(at 0 1.397 180)
			(size 0.889 0.9906)
			(layers "F.Cu" "F.Mask" "F.Paste")
			(net "GND")
		)
		(zone
			(layer "F.Cu")
			(hatch none 0.5)
			(connect_pads
				(clearance 0)
			)
			(min_thickness 0.25)
			(keepout
				(tracks not_allowed)
				(vias allowed)
				(pads allowed)
				(copperpour not_allowed)
				(footprints allowed)
			)
			(placement
				(enabled no)
				(sheetname "")
			)
			(fill
				(thermal_gap 0.5)
				(thermal_bridge_width 0.5)
				(island_removal_mode 0)
			)
			(polygon
				(pts
					(xy 82.903568 -3.8481) (xy 82.903568 -2.8575) (xy 83.411568 -2.8575) (xy 83.411568 -3.8481)
				)
			)
		)
		(zone
			(layer "F.Cu")
			(hatch none 0.5)
			(connect_pads
				(clearance 0)
			)
			(min_thickness 0.25)
			(keepout
				(tracks allowed)
				(vias not_allowed)
				(pads allowed)
				(copperpour not_allowed)
				(footprints allowed)
			)
			(placement
				(enabled no)
				(sheetname "")
			)
			(fill
				(thermal_gap 0.5)
				(thermal_bridge_width 0.5)
				(island_removal_mode 0)
			)
			(polygon
				(pts
					(xy 82.903568 -3.8481) (xy 82.903568 -2.8575) (xy 83.411568 -2.8575) (xy 83.411568 -3.8481)
				)
			)
		)
	)
)
